#ISCELL
  pure_quanta quanta_title_block_c *
  *
#CELL
  pure_quanta lcmxo3lf9400c5bg484c *
  page81_i1
#ISCELL
  standard offpage *
  page81_i10
#CELL
  pure_quanta q_res *
  page81_i100
#CELL
  pure_quanta q_res *
  page81_i101
#CELL
  pure_quanta q_res *
  page81_i102
#CELL
  pure_quanta q_res *
  page81_i103
#CELL
  pure_quanta q_res *
  page81_i104
#CELL
  pure_quanta q_res *
  page81_i105
#CELL
  pure_quanta q_res *
  page81_i106
#CELL
  pure_quanta q_res *
  page81_i107
#CELL
  pure_quanta q_res *
  page81_i108
#CELL
  pure_quanta q_res *
  page81_i109
#ISCELL
  standard offpage *
  page81_i11
#CELL
  pure_quanta q_res *
  page81_i110
#CELL
  pure_quanta q_res *
  page81_i111
#CELL
  pure_quanta q_res *
  page81_i112
#CELL
  pure_quanta q_res *
  page81_i113
#ISCELL
  standard offpage *
  page81_i114
#ISCELL
  standard offpage *
  page81_i115
#ISCELL
  standard offpage *
  page81_i116
#ISCELL
  standard offpage *
  page81_i117
#ISCELL
  standard offpage *
  page81_i118
#ISCELL
  standard offpage *
  page81_i119
#ISCELL
  standard offpage *
  page81_i12
#ISCELL
  standard offpage *
  page81_i120
#ISCELL
  standard offpage *
  page81_i121
#ISCELL
  standard offpage *
  page81_i122
#ISCELL
  standard offpage *
  page81_i123
#ISCELL
  standard offpage *
  page81_i124
#ISCELL
  standard offpage *
  page81_i125
#ISCELL
  standard offpage *
  page81_i129
#ISCELL
  standard offpage *
  page81_i13
#ISCELL
  standard offpage *
  page81_i130
#ISCELL
  standard offpage *
  page81_i131
#ISCELL
  standard offpage *
  page81_i132
#ISCELL
  standard offpage *
  page81_i133
#ISCELL
  standard offpage *
  page81_i134
#ISCELL
  standard offpage *
  page81_i135
#ISCELL
  standard offpage *
  page81_i136
#ISCELL
  standard offpage *
  page81_i137
#ISCELL
  standard offpage *
  page81_i138
#ISCELL
  standard offpage *
  page81_i139
#ISCELL
  standard offpage *
  page81_i14
#CELL
  pure_quanta q_res *
  page81_i140
#CELL
  pure_quanta lcmxo3lf9400c5bg484c *
  page81_i141
#ISCELL
  pure_quanta_power universal_power *
  page81_i142
#CELL
  pure_quanta lcmxo3lf9400c5bg484c *
  page81_i143
#ISCELL
  standard offpage *
  page81_i145
#CELL
  pure_quanta q_res *
  page81_i146
#ISCELL
  standard offpage *
  page81_i147
#ISCELL
  standard offpage *
  page81_i148
#ISCELL
  standard offpage *
  page81_i149
#ISCELL
  standard offpage *
  page81_i15
#ISCELL
  standard offpage *
  page81_i150
#ISCELL
  standard offpage *
  page81_i153
#ISCELL
  standard offpage *
  page81_i154
#ISCELL
  standard offpage *
  page81_i155
#ISCELL
  standard offpage *
  page81_i156
#ISCELL
  standard offpage *
  page81_i157
#ISCELL
  standard offpage *
  page81_i158
#ISCELL
  standard offpage *
  page81_i159
#ISCELL
  standard offpage *
  page81_i16
#ISCELL
  standard offpage *
  page81_i160
#CELL
  pure_quanta q_res *
  page81_i164
#CELL
  pure_quanta q_res *
  page81_i165
#ISCELL
  standard offpage *
  page81_i166
#ISCELL
  standard offpage *
  page81_i167
#CELL
  pure_quanta q_res *
  page81_i168
#CELL
  pure_quanta q_res *
  page81_i169
#ISCELL
  standard offpage *
  page81_i17
#ISCELL
  standard offpage *
  page81_i170
#ISCELL
  standard offpage *
  page81_i171
#ISCELL
  standard offpage *
  page81_i172
#ISCELL
  standard offpage *
  page81_i173
#ISCELL
  standard offpage *
  page81_i174
#ISCELL
  standard offpage *
  page81_i175
#CELL
  pure_quanta q_res *
  page81_i176
#ISCELL
  standard offpage *
  page81_i177
#CELL
  pure_quanta q_res *
  page81_i178
#ISCELL
  standard offpage *
  page81_i179
#ISCELL
  standard offpage *
  page81_i18
#CELL
  pure_quanta q_res *
  page81_i180
#ISCELL
  standard offpage *
  page81_i181
#ISCELL
  standard offpage *
  page81_i182
#ISCELL
  standard offpage *
  page81_i19
#ISCELL
  pure_quanta_power gnd *
  page81_i2
#ISCELL
  standard offpage *
  page81_i20
#ISCELL
  standard offpage *
  page81_i21
#ISCELL
  standard offpage *
  page81_i22
#ISCELL
  standard offpage *
  page81_i23
#ISCELL
  standard offpage *
  page81_i24
#ISCELL
  standard offpage *
  page81_i25
#ISCELL
  standard offpage *
  page81_i26
#ISCELL
  standard offpage *
  page81_i27
#ISCELL
  standard offpage *
  page81_i28
#ISCELL
  standard offpage *
  page81_i29
#ISCELL
  standard offpage *
  page81_i3
#ISCELL
  standard offpage *
  page81_i30
#ISCELL
  standard offpage *
  page81_i32
#ISCELL
  standard offpage *
  page81_i33
#ISCELL
  standard offpage *
  page81_i34
#ISCELL
  standard offpage *
  page81_i35
#ISCELL
  standard offpage *
  page81_i36
#ISCELL
  standard offpage *
  page81_i37
#ISCELL
  standard offpage *
  page81_i38
#ISCELL
  standard offpage *
  page81_i39
#ISCELL
  standard offpage *
  page81_i4
#ISCELL
  standard offpage *
  page81_i40
#ISCELL
  standard offpage *
  page81_i41
#ISCELL
  standard offpage *
  page81_i42
#ISCELL
  standard offpage *
  page81_i43
#CELL
  pure_quanta q_res *
  page81_i44
#CELL
  pure_quanta q_res *
  page81_i45
#CELL
  pure_quanta q_res *
  page81_i46
#CELL
  pure_quanta q_res *
  page81_i47
#CELL
  pure_quanta q_res *
  page81_i48
#CELL
  pure_quanta q_res *
  page81_i49
#ISCELL
  standard offpage *
  page81_i5
#CELL
  pure_quanta q_res *
  page81_i50
#CELL
  pure_quanta q_res *
  page81_i51
#CELL
  pure_quanta q_res *
  page81_i52
#CELL
  pure_quanta q_res *
  page81_i53
#CELL
  pure_quanta q_res *
  page81_i54
#CELL
  pure_quanta q_res *
  page81_i55
#CELL
  pure_quanta q_res *
  page81_i56
#CELL
  pure_quanta q_res *
  page81_i57
#CELL
  pure_quanta q_res *
  page81_i58
#CELL
  pure_quanta q_res *
  page81_i59
#CELL
  pure_quanta q_res *
  page81_i60
#CELL
  pure_quanta q_res *
  page81_i61
#CELL
  pure_quanta q_res *
  page81_i62
#CELL
  pure_quanta q_res *
  page81_i63
#CELL
  pure_quanta q_res *
  page81_i64
#CELL
  pure_quanta q_res *
  page81_i65
#CELL
  pure_quanta q_res *
  page81_i66
#CELL
  pure_quanta q_res *
  page81_i67
#CELL
  pure_quanta q_res *
  page81_i68
#CELL
  pure_quanta q_res *
  page81_i69
#CELL
  pure_quanta q_res *
  page81_i70
#CELL
  pure_quanta q_res *
  page81_i71
#CELL
  pure_quanta q_res *
  page81_i72
#CELL
  pure_quanta q_res *
  page81_i73
#CELL
  pure_quanta q_res *
  page81_i74
#CELL
  pure_quanta q_res *
  page81_i75
#ISCELL
  standard offpage *
  page81_i76
#CELL
  pure_quanta q_res *
  page81_i77
#ISCELL
  pure_quanta_power universal_power *
  page81_i78
#ISCELL
  pure_quanta_power vcc_core *
  page81_i79
#CELL
  pure_quanta q_res *
  page81_i80
#CELL
  pure_quanta q_res *
  page81_i81
#CELL
  pure_quanta q_res *
  page81_i82
#CELL
  pure_quanta q_res *
  page81_i83
#CELL
  pure_quanta q_res *
  page81_i84
#CELL
  pure_quanta q_res *
  page81_i85
#CELL
  pure_quanta q_res *
  page81_i86
#ISCELL
  standard offpage *
  page81_i87
#ISCELL
  standard offpage *
  page81_i88
#ISCELL
  standard offpage *
  page81_i89
#ISCELL
  standard offpage *
  page81_i9
#ISCELL
  standard offpage *
  page81_i90
#ISCELL
  standard offpage *
  page81_i91
#ISCELL
  standard offpage *
  page81_i92
#ISCELL
  standard offpage *
  page81_i93
#ISCELL
  standard offpage *
  page81_i94
#ISCELL
  standard offpage *
  page81_i95
#ISCELL
  standard offpage *
  page81_i96
#ISCELL
  pure_quanta_power universal_power *
  page81_i97
#ISCELL
  pure_quanta_power vcc_core *
  page81_i98
#CELL
  pure_quanta q_res *
  page81_i99
